# T6G (Grand Teton) — schematic netlist excerpt (pin names and nets, part order shuffled) for the footprints in the layout excerpt that follows; sources: Cadence DE-HDL packaged netlist, KiCad conversion of 04192023_DAF0TMB3IC0_F0TG_MB_C_brd_V02_OCP.brd

C2403  Q_CAP  22UF 4V 20% X6S  pkg C0402  page 73 : A = PVDDCR_CPU1_P1 ; B = GND
PC587_1  Q_CAP  22UF 16V 20% X6S  pkg C0805  page 198 : A = SW_P12V_AUX_PVDDCR_SOC_P0_FLT ; B = GND
R1897  Q_RES  100 1% CHIP  pkg 0402LF  page 132 : A = OCP_SFF_ISO_BIF1_EN ; B = GND

(kicad_pcb
	(version 20260206)
	(generator "pcbnew")
	(generator_version "10.0")
	(general
		(thickness 1.6)
		(legacy_teardrops no)
	)
	(paper "A4")
	(title_block
		(title "04192023_DAF0TMB3IC0_F0TG_MB_C_brd_V02_OCP.brd")
		(comment 1 "Grand Teton / footprints 5746-5748 of 8354")
	)
	(layers
		(0 "F.Cu" signal "TOP")
		(4 "In1.Cu" signal "GND")
		(6 "In2.Cu" signal "IN1")
		(8 "In3.Cu" signal "GND1")
		(10 "In4.Cu" signal "IN2")
		(12 "In5.Cu" signal "GND2")
		(14 "In6.Cu" signal "IN3")
		(16 "In7.Cu" signal "GND3")
		(18 "In8.Cu" signal "VCC")
		(20 "In9.Cu" signal "VCC1")
		(22 "In10.Cu" signal "GND4")
		(24 "In11.Cu" signal "IN4")
		(26 "In12.Cu" signal "GND5")
		(28 "In13.Cu" signal "IN5")
		(30 "In14.Cu" signal "GND6")
		(32 "In15.Cu" signal "IN6")
		(34 "In16.Cu" signal "GND7")
		(2 "B.Cu" signal "BOTTOM")
		(9 "F.Adhes" user "F.Adhesive")
		(11 "B.Adhes" user "B.Adhesive")
		(13 "F.Paste" user "Package Geometry/Pastemask Top")
		(15 "B.Paste" user "Package Geometry/Pastemask Bottom")
		(5 "F.SilkS" user "Ref Des/Silkscreen Top")
		(7 "B.SilkS" user "Ref Des/Silkscreen Bottom")
		(1 "F.Mask" user "Board Geometry/Soldermask Top")
		(3 "B.Mask" user "Board Geometry/Soldermask Bottom")
		(17 "Dwgs.User" user "User.Drawings")
		(19 "Cmts.User" user "User.Comments")
		(21 "Eco1.User" user "User.Eco1")
		(23 "Eco2.User" user "User.Eco2")
		(25 "Edge.Cuts" user "Board Geometry/Outline")
		(27 "Margin" user)
		(31 "F.CrtYd" user "Package Geometry/Place Bound Top")
		(29 "B.CrtYd" user "Package Geometry/Place Bound Bottom")
		(35 "F.Fab" user "Ref Des/Assembly Top")
		(33 "B.Fab" user "Ref Des/Assembly Bottom")
	)
	(footprint ""
		(layer "B.Cu")
		(at 396.611856 -173.394878 90)
		(property "Reference" "PC587_1"
			(at 0 0 90)
			(layer "B.SilkS")
			(hide yes)
			(effects
				(font
					(size 1.27 1.27)
				)
				(justify mirror)
			)
		)
		(property "Value" ""
			(at 0 0 90)
			(layer "B.Fab")
			(effects
				(font
					(size 1.27 1.27)
				)
				(justify mirror)
			)
		)
		(duplicate_pad_numbers_are_jumpers no)
		(fp_line
			(start 1.524 -0.762)
			(end -1.524 -0.762)
			(stroke
				(width 0.1524)
				(type default)
			)
			(layer "B.SilkS")
		)
		(fp_line
			(start -1.524 -0.762)
			(end -1.524 0.762)
			(stroke
				(width 0.1524)
				(type default)
			)
			(layer "B.SilkS")
		)
		(fp_line
			(start 1.524 0.762)
			(end 1.524 -0.762)
			(stroke
				(width 0.1524)
				(type default)
			)
			(layer "B.SilkS")
		)
		(fp_line
			(start -1.524 0.762)
			(end 1.524 0.762)
			(stroke
				(width 0.1524)
				(type default)
			)
			(layer "B.SilkS")
		)
		(fp_line
			(start 1.1049 -0.724916)
			(end 1.1049 0.724916)
			(stroke
				(width 0.1)
				(type default)
			)
			(layer "B.Fab")
		)
		(fp_line
			(start -1.1049 -0.724916)
			(end 1.1049 -0.724916)
			(stroke
				(width 0.1)
				(type default)
			)
			(layer "B.Fab")
		)
		(fp_line
			(start 1.1049 0.724916)
			(end -1.1049 0.724916)
			(stroke
				(width 0.1)
				(type default)
			)
			(layer "B.Fab")
		)
		(fp_line
			(start -1.1049 0.724916)
			(end -1.1049 -0.724916)
			(stroke
				(width 0.1)
				(type default)
			)
			(layer "B.Fab")
		)
		(pad "1" smd rect
			(at 0.889 0 90)
			(size 1.016 1.27)
			(layers "B.Cu" "B.Mask" "B.Paste")
			(net "SW_P12V_AUX_PVDDCR_SOC_P0_FLT")
		)
		(pad "2" smd rect
			(at -0.889 0 90)
			(size 1.016 1.27)
			(layers "B.Cu" "B.Mask" "B.Paste")
			(net "GND")
		)
	)
	(footprint ""
		(layer "B.Cu")
		(at 435.050946 -26.886408 90)
		(property "Reference" "R1897"
			(at 0 0 90)
			(layer "B.SilkS")
			(hide yes)
			(effects
				(font
					(size 1.27 1.27)
				)
				(justify mirror)
			)
		)
		(property "Value" ""
			(at 0 0 90)
			(layer "B.Fab")
			(effects
				(font
					(size 1.27 1.27)
				)
				(justify mirror)
			)
		)
		(duplicate_pad_numbers_are_jumpers no)
		(fp_line
			(start 0.7874 -0.4064)
			(end -0.7874 -0.4064)
			(stroke
				(width 0.1524)
				(type default)
			)
			(layer "B.SilkS")
		)
		(fp_line
			(start -0.7874 -0.4064)
			(end -0.7874 0.4064)
			(stroke
				(width 0.1524)
				(type default)
			)
			(layer "B.SilkS")
		)
		(fp_line
			(start 0.7874 0.4064)
			(end 0.7874 -0.4064)
			(stroke
				(width 0.1524)
				(type default)
			)
			(layer "B.SilkS")
		)
		(fp_line
			(start -0.7874 0.4064)
			(end 0.7874 0.4064)
			(stroke
				(width 0.1524)
				(type default)
			)
			(layer "B.SilkS")
		)
		(fp_line
			(start 0.67945 -0.305054)
			(end 0.12065 -0.305054)
			(stroke
				(width 0.1)
				(type default)
			)
			(layer "B.Fab")
		)
		(fp_line
			(start 0.12065 -0.305054)
			(end 0.12065 -0.2794)
			(stroke
				(width 0.1)
				(type default)
			)
			(layer "B.Fab")
		)
		(fp_line
			(start -0.12065 -0.3048)
			(end -0.67945 -0.3048)
			(stroke
				(width 0.1)
				(type default)
			)
			(layer "B.Fab")
		)
		(fp_line
			(start -0.67945 -0.3048)
			(end -0.67945 0.3048)
			(stroke
				(width 0.1)
				(type default)
			)
			(layer "B.Fab")
		)
		(fp_line
			(start 0.12065 -0.2794)
			(end -0.12065 -0.2794)
			(stroke
				(width 0.1)
				(type default)
			)
			(layer "B.Fab")
		)
		(fp_line
			(start -0.12065 -0.2794)
			(end -0.12065 -0.3048)
			(stroke
				(width 0.1)
				(type default)
			)
			(layer "B.Fab")
		)
		(fp_line
			(start 0.12065 0.2794)
			(end 0.12065 0.3048)
			(stroke
				(width 0.1)
				(type default)
			)
			(layer "B.Fab")
		)
		(fp_line
			(start -0.120396 0.2794)
			(end 0.12065 0.2794)
			(stroke
				(width 0.1)
				(type default)
			)
			(layer "B.Fab")
		)
		(fp_line
			(start 0.67945 0.3048)
			(end 0.67945 -0.305054)
			(stroke
				(width 0.1)
				(type default)
			)
			(layer "B.Fab")
		)
		(fp_line
			(start 0.12065 0.3048)
			(end 0.67945 0.3048)
			(stroke
				(width 0.1)
				(type default)
			)
			(layer "B.Fab")
		)
		(fp_line
			(start -0.120396 0.3048)
			(end -0.120396 0.2794)
			(stroke
				(width 0.1)
				(type default)
			)
			(layer "B.Fab")
		)
		(fp_line
			(start -0.67945 0.3048)
			(end -0.120396 0.3048)
			(stroke
				(width 0.1)
				(type default)
			)
			(layer "B.Fab")
		)
		(pad "1" smd circle
			(at 0.40005 0 270)
			(size 0 0)
			(layers "B.Cu" "B.Mask" "B.Paste")
			(net "OCP_SFF_ISO_BIF1_EN")
		)
		(pad "2" smd circle
			(at -0.40005 0 270)
			(size 0 0)
			(layers "B.Cu" "B.Mask" "B.Paste")
			(net "GND")
		)
	)
	(footprint ""
		(layer "B.Cu")
		(at 106.466386 -267.529564)
		(property "Reference" "C2403"
			(at 0 0 0)
			(layer "B.SilkS")
			(hide yes)
			(effects
				(font
					(size 1.27 1.27)
				)
				(justify mirror)
			)
		)
		(property "Value" ""
			(at 0 0 0)
			(layer "B.Fab")
			(effects
				(font
					(size 1.27 1.27)
				)
				(justify mirror)
			)
		)
		(duplicate_pad_numbers_are_jumpers no)
		(fp_line
			(start -0.7874 -0.4064)
			(end -0.7874 0.4064)
			(stroke
				(width 0.1524)
				(type default)
			)
			(layer "B.SilkS")
		)
		(fp_line
			(start -0.7874 0.4064)
			(end 0.7874 0.4064)
			(stroke
				(width 0.1524)
				(type default)
			)
			(layer "B.SilkS")
		)
		(fp_line
			(start 0.7874 -0.4064)
			(end -0.7874 -0.4064)
			(stroke
				(width 0.1524)
				(type default)
			)
			(layer "B.SilkS")
		)
		(fp_line
			(start 0.7874 0.4064)
			(end 0.7874 -0.4064)
			(stroke
				(width 0.1524)
				(type default)
			)
			(layer "B.SilkS")
		)
		(fp_line
			(start -0.67945 -0.3048)
			(end -0.67945 0.3048)
			(stroke
				(width 0.1)
				(type default)
			)
			(layer "B.Fab")
		)
		(fp_line
			(start -0.67945 0.3048)
			(end -0.120396 0.3048)
			(stroke
				(width 0.1)
				(type default)
			)
			(layer "B.Fab")
		)
		(fp_line
			(start -0.12065 -0.3048)
			(end -0.67945 -0.3048)
			(stroke
				(width 0.1)
				(type default)
			)
			(layer "B.Fab")
		)
		(fp_line
			(start -0.12065 -0.2794)
			(end -0.12065 -0.3048)
			(stroke
				(width 0.1)
				(type default)
			)
			(layer "B.Fab")
		)
		(fp_line
			(start -0.120396 0.2794)
			(end 0.12065 0.2794)
			(stroke
				(width 0.1)
				(type default)
			)
			(layer "B.Fab")
		)
		(fp_line
			(start -0.120396 0.3048)
			(end -0.120396 0.2794)
			(stroke
				(width 0.1)
				(type default)
			)
			(layer "B.Fab")
		)
		(fp_line
			(start 0.12065 -0.305054)
			(end 0.12065 -0.2794)
			(stroke
				(width 0.1)
				(type default)
			)
			(layer "B.Fab")
		)
		(fp_line
			(start 0.12065 -0.2794)
			(end -0.12065 -0.2794)
			(stroke
				(width 0.1)
				(type default)
			)
			(layer "B.Fab")
		)
		(fp_line
			(start 0.12065 0.2794)
			(end 0.12065 0.3048)
			(stroke
				(width 0.1)
				(type default)
			)
			(layer "B.Fab")
		)
		(fp_line
			(start 0.12065 0.3048)
			(end 0.67945 0.3048)
			(stroke
				(width 0.1)
				(type default)
			)
			(layer "B.Fab")
		)
		(fp_line
			(start 0.67945 -0.305054)
			(end 0.12065 -0.305054)
			(stroke
				(width 0.1)
				(type default)
			)
			(layer "B.Fab")
		)
		(fp_line
			(start 0.67945 0.3048)
			(end 0.67945 -0.305054)
			(stroke
				(width 0.1)
				(type default)
			)
			(layer "B.Fab")
		)
		(pad "1" smd circle
			(at 0.40005 0 180)
			(size 0 0)
			(layers "B.Cu" "B.Mask" "B.Paste")
			(net "PVDDCR_CPU1_P1")
		)
		(pad "2" smd circle
			(at -0.40005 0 180)
			(size 0 0)
			(layers "B.Cu" "B.Mask" "B.Paste")
			(net "GND")
		)
	)
)
